FILE_TYPE = MACRO_DRAWING;
SET COLOR_WIRE YELLOW;
SET COLOR_PROP ORANGE;
SET COLOR_DOT WHITE;
SET COLOR_ARC YELLOW;
SET COLOR_BODY GREEN;
SET COLOR_NOTE PURPLE;
SET PROP_DISPLAY VALUE;
SET PAGE_NUMBER P5;
SET PATH_NUMBER P0;
FORCEADD QUANTA_TITLE_BLOCK_C..1
(5325 -1575);
FORCEPROP 0 LAST CDS_CON_LAST_MODIFIED Fri Aug 25 17:25:34 2023
J 0
(3440 -1560);
DISPLAY INVISIBLE (3440 -1560);
FORCEPROP 2 LAST Q_DEPT 
J 1
(1562 -1526);
DISPLAY 1.957447 (1562 -1526);
PAINT GREEN (1562 -1526);
FORCEPROP 1 LAST CUSTOM_TXT_CDS <CON_LAST_MODIFIED>
J 0
(3440 -1560);
DISPLAY 0.978723 (3440 -1560);
FORCEPROP 2 LAST CUSTOM_TXT_CDS <XR_PAGE_TITLE>
J 0
(-2565 3675);
DISPLAY 0.638298 (-2565 3675);
PAINT PINK (-2565 3675);
DISPLAY INVISIBLE (-2565 3675);
FORCEPROP 1 LAST CUSTOM_TXT_CDS <NAME_2>
J 0
(2150 -1525);
FORCEPROP 1 LAST CUSTOM_TXT_CDS <NAME_1>
J 0
(2150 -1400);
FORCEPROP 1 LAST CUSTOM_TXT_CDS <Q_NUMBER>
J 0
(3922 -1472);
DISPLAY 1.212766 (3922 -1472);
FORCEPROP 1 LAST CUSTOM_TXT_CDS <Q_PROJ>
J 0
(2943 -1473);
DISPLAY 1.212766 (2943 -1473);
FORCEPROP 1 LAST CUSTOM_TXT_CDS <Q_REV>
J 0
(5141 -1472);
DISPLAY 1.212766 (5141 -1472);
FORCEPROP 1 LAST CUSTOM_TXT_CDS <CON_PAGE_NUM> OF <CON_TOTAL_PAGES>
J 0
(4879 -1557);
DISPLAY 0.978723 (4879 -1557);
FORCEPROP 1 LAST Q_TITLE SPI MUX FOR BIOS
J 0
(-4041 -1549);
DISPLAY 2.446809 (-4041 -1549);
PAINT GREEN (-4041 -1549);
FORCEPROP 2 LAST PAGE_BORDER TRUE
J 0
(-2565 3675);
DISPLAY 0.638298 (-2565 3675);
PAINT PINK (-2565 3675);
DISPLAY INVISIBLE (-2565 3675);
FORCEPROP 1 LAST CDS_LMAN_SYM_OUTLINE -9475,6775,100,-125
J 0
(5325 -1575);
DISPLAY 0.468085 (5325 -1575);
PAINT GREEN (5325 -1575);
DISPLAY INVISIBLE (5325 -1575);
FORCEPROP 2 LAST CDS_LIB pure_quanta
J 0
(5325 -1575);
DISPLAY INVISIBLE (5325 -1575);
FORCEPROP 1 LAST COMMENT_BODY TRUE
J 0
(5337 -1588);
DISPLAY 0.978723 (5337 -1588);
PAINT PEACH (5337 -1588);
DISPLAY INVISIBLE (5337 -1588);
FORCEPROP 2 LAST CDS_XR_PAGE_TITLE CR-5 : @SCM_LIB.SCM(SCH_1):PAGE5
J 0
(-2565 3675);
DISPLAY 0.638298 (-2565 3675);
PAINT PINK (-2565 3675);
DISPLAY INVISIBLE (-2565 3675);
FORCENOTE
$CDS_IMAGE|SPI_MUX_20201203.jpg|9013|2555
(700 2075) 0;
DISPLAY LEFT (700 2075);
QUIT
